(kicad_pcb
	(version 20260206)
	(generator "pcbnew")
	(generator_version "10.0")
	(general
		(thickness 1.6)
		(legacy_teardrops no)
	)
	(paper "A4")
	(title_block
		(title "12092022_DA0F0TMDCD0_F0T_Management_Board_D_brd_V3_OCP.brd")
		(comment 1 "Grand Teton / footprints 1308-1313 of 1440")
	)
	(layers
		(0 "F.Cu" signal "TOP")
		(4 "In1.Cu" signal "GND")
		(6 "In2.Cu" signal "IN1")
		(8 "In3.Cu" signal "GND1")
		(10 "In4.Cu" signal "IN2")
		(12 "In5.Cu" signal "VCC")
		(14 "In6.Cu" signal "VCC1")
		(16 "In7.Cu" signal "IN3")
		(18 "In8.Cu" signal "GND2")
		(20 "In9.Cu" signal "IN4")
		(22 "In10.Cu" signal "GND3")
		(2 "B.Cu" signal "BOTTOM")
		(9 "F.Adhes" user "F.Adhesive")
		(11 "B.Adhes" user "B.Adhesive")
		(13 "F.Paste" user "Package Geometry/Pastemask Top")
		(15 "B.Paste" user "Package Geometry/Pastemask Bottom")
		(5 "F.SilkS" user "Ref Des/Silkscreen Top")
		(7 "B.SilkS" user "Ref Des/Silkscreen Bottom")
		(1 "F.Mask" user "Board Geometry/Soldermask Top")
		(3 "B.Mask" user "Board Geometry/Soldermask Bottom")
		(17 "Dwgs.User" user "User.Drawings")
		(19 "Cmts.User" user "User.Comments")
		(21 "Eco1.User" user "User.Eco1")
		(23 "Eco2.User" user "User.Eco2")
		(25 "Edge.Cuts" user "Board Geometry/Outline")
		(27 "Margin" user)
		(31 "F.CrtYd" user "Package Geometry/Place Bound Top")
		(29 "B.CrtYd" user "Package Geometry/Place Bound Bottom")
		(35 "F.Fab" user "Ref Des/Assembly Top")
		(33 "B.Fab" user "Ref Des/Assembly Bottom")
	)
	(footprint ""
		(layer "B.Cu")
		(at 47.879 -52.1462 -90)
		(property "Reference" "R61"
			(at 0 0 90)
			(layer "B.SilkS")
			(hide yes)
			(effects
				(font
					(size 1.27 1.27)
				)
				(justify mirror)
			)
		)
		(property "Value" ""
			(at 0 0 90)
			(layer "B.Fab")
			(effects
				(font
					(size 1.27 1.27)
				)
				(justify mirror)
			)
		)
		(duplicate_pad_numbers_are_jumpers no)
		(fp_line
			(start -0.7874 0.4064)
			(end 0.7874 0.4064)
			(stroke
				(width 0.1524)
				(type default)
			)
			(layer "B.SilkS")
		)
		(fp_line
			(start 0.7874 0.4064)
			(end 0.7874 -0.4064)
			(stroke
				(width 0.1524)
				(type default)
			)
			(layer "B.SilkS")
		)
		(fp_line
			(start -0.7874 -0.4064)
			(end -0.7874 0.4064)
			(stroke
				(width 0.1524)
				(type default)
			)
			(layer "B.SilkS")
		)
		(fp_line
			(start 0.7874 -0.4064)
			(end -0.7874 -0.4064)
			(stroke
				(width 0.1524)
				(type default)
			)
			(layer "B.SilkS")
		)
		(fp_line
			(start -0.67945 0.3048)
			(end -0.120396 0.3048)
			(stroke
				(width 0.1)
				(type default)
			)
			(layer "B.Fab")
		)
		(fp_line
			(start -0.120396 0.3048)
			(end -0.120396 0.2794)
			(stroke
				(width 0.1)
				(type default)
			)
			(layer "B.Fab")
		)
		(fp_line
			(start 0.12065 0.3048)
			(end 0.67945 0.3048)
			(stroke
				(width 0.1)
				(type default)
			)
			(layer "B.Fab")
		)
		(fp_line
			(start 0.67945 0.3048)
			(end 0.67945 -0.305054)
			(stroke
				(width 0.1)
				(type default)
			)
			(layer "B.Fab")
		)
		(fp_line
			(start -0.120396 0.2794)
			(end 0.12065 0.2794)
			(stroke
				(width 0.1)
				(type default)
			)
			(layer "B.Fab")
		)
		(fp_line
			(start 0.12065 0.2794)
			(end 0.12065 0.3048)
			(stroke
				(width 0.1)
				(type default)
			)
			(layer "B.Fab")
		)
		(fp_line
			(start -0.12065 -0.2794)
			(end -0.12065 -0.3048)
			(stroke
				(width 0.1)
				(type default)
			)
			(layer "B.Fab")
		)
		(fp_line
			(start 0.12065 -0.2794)
			(end -0.12065 -0.2794)
			(stroke
				(width 0.1)
				(type default)
			)
			(layer "B.Fab")
		)
		(fp_line
			(start -0.67945 -0.3048)
			(end -0.67945 0.3048)
			(stroke
				(width 0.1)
				(type default)
			)
			(layer "B.Fab")
		)
		(fp_line
			(start -0.12065 -0.3048)
			(end -0.67945 -0.3048)
			(stroke
				(width 0.1)
				(type default)
			)
			(layer "B.Fab")
		)
		(fp_line
			(start 0.12065 -0.305054)
			(end 0.12065 -0.2794)
			(stroke
				(width 0.1)
				(type default)
			)
			(layer "B.Fab")
		)
		(fp_line
			(start 0.67945 -0.305054)
			(end 0.12065 -0.305054)
			(stroke
				(width 0.1)
				(type default)
			)
			(layer "B.Fab")
		)
		(pad "1" smd circle
			(at 0.40005 0 90)
			(size 0 0)
			(layers "B.Cu" "B.Mask" "B.Paste")
			(net "P3V3_AUX")
		)
		(pad "2" smd circle
			(at -0.40005 0 90)
			(size 0 0)
			(layers "B.Cu" "B.Mask" "B.Paste")
			(net "IRQ_BMC_PCH_NMI_N")
		)
	)
	(footprint ""
		(layer "B.Cu")
		(at 47.879 -63.9445 90)
		(property "Reference" "R449"
			(at 0 0 90)
			(layer "B.SilkS")
			(hide yes)
			(effects
				(font
					(size 1.27 1.27)
				)
				(justify mirror)
			)
		)
		(property "Value" ""
			(at 0 0 90)
			(layer "B.Fab")
			(effects
				(font
					(size 1.27 1.27)
				)
				(justify mirror)
			)
		)
		(duplicate_pad_numbers_are_jumpers no)
		(fp_line
			(start 0.7874 -0.4064)
			(end -0.7874 -0.4064)
			(stroke
				(width 0.1524)
				(type default)
			)
			(layer "B.SilkS")
		)
		(fp_line
			(start -0.7874 -0.4064)
			(end -0.7874 0.4064)
			(stroke
				(width 0.1524)
				(type default)
			)
			(layer "B.SilkS")
		)
		(fp_line
			(start 0.7874 0.4064)
			(end 0.7874 -0.4064)
			(stroke
				(width 0.1524)
				(type default)
			)
			(layer "B.SilkS")
		)
		(fp_line
			(start -0.7874 0.4064)
			(end 0.7874 0.4064)
			(stroke
				(width 0.1524)
				(type default)
			)
			(layer "B.SilkS")
		)
		(fp_line
			(start 0.67945 -0.305054)
			(end 0.12065 -0.305054)
			(stroke
				(width 0.1)
				(type default)
			)
			(layer "B.Fab")
		)
		(fp_line
			(start 0.12065 -0.305054)
			(end 0.12065 -0.2794)
			(stroke
				(width 0.1)
				(type default)
			)
			(layer "B.Fab")
		)
		(fp_line
			(start -0.12065 -0.3048)
			(end -0.67945 -0.3048)
			(stroke
				(width 0.1)
				(type default)
			)
			(layer "B.Fab")
		)
		(fp_line
			(start -0.67945 -0.3048)
			(end -0.67945 0.3048)
			(stroke
				(width 0.1)
				(type default)
			)
			(layer "B.Fab")
		)
		(fp_line
			(start 0.12065 -0.2794)
			(end -0.12065 -0.2794)
			(stroke
				(width 0.1)
				(type default)
			)
			(layer "B.Fab")
		)
		(fp_line
			(start -0.12065 -0.2794)
			(end -0.12065 -0.3048)
			(stroke
				(width 0.1)
				(type default)
			)
			(layer "B.Fab")
		)
		(fp_line
			(start 0.12065 0.2794)
			(end 0.12065 0.3048)
			(stroke
				(width 0.1)
				(type default)
			)
			(layer "B.Fab")
		)
		(fp_line
			(start -0.120396 0.2794)
			(end 0.12065 0.2794)
			(stroke
				(width 0.1)
				(type default)
			)
			(layer "B.Fab")
		)
		(fp_line
			(start 0.67945 0.3048)
			(end 0.67945 -0.305054)
			(stroke
				(width 0.1)
				(type default)
			)
			(layer "B.Fab")
		)
		(fp_line
			(start 0.12065 0.3048)
			(end 0.67945 0.3048)
			(stroke
				(width 0.1)
				(type default)
			)
			(layer "B.Fab")
		)
		(fp_line
			(start -0.120396 0.3048)
			(end -0.120396 0.2794)
			(stroke
				(width 0.1)
				(type default)
			)
			(layer "B.Fab")
		)
		(fp_line
			(start -0.67945 0.3048)
			(end -0.120396 0.3048)
			(stroke
				(width 0.1)
				(type default)
			)
			(layer "B.Fab")
		)
		(pad "1" smd circle
			(at 0.40005 0 270)
			(size 0 0)
			(layers "B.Cu" "B.Mask" "B.Paste")
			(net "SMB_BMC_ALERT10_N")
		)
		(pad "2" smd circle
			(at -0.40005 0 270)
			(size 0 0)
			(layers "B.Cu" "B.Mask" "B.Paste")
			(net "SMB_BMC_ALERT10_R_N")
		)
	)
	(footprint ""
		(layer "B.Cu")
		(at 18.259298 -94.786958 180)
		(property "Reference" "C141"
			(at 0 0 0)
			(layer "B.SilkS")
			(hide yes)
			(effects
				(font
					(size 1.27 1.27)
				)
				(justify mirror)
			)
		)
		(property "Value" ""
			(at 0 0 0)
			(layer "B.Fab")
			(effects
				(font
					(size 1.27 1.27)
				)
				(justify mirror)
			)
		)
		(duplicate_pad_numbers_are_jumpers no)
		(fp_line
			(start 0.69215 0.2921)
			(end 0.69215 -0.2921)
			(stroke
				(width 0.1524)
				(type default)
			)
			(layer "B.SilkS")
		)
		(fp_line
			(start 0.69215 -0.2921)
			(end -0.69215 -0.2921)
			(stroke
				(width 0.1524)
				(type default)
			)
			(layer "B.SilkS")
		)
		(fp_line
			(start -0.69215 0.2921)
			(end 0.69215 0.2921)
			(stroke
				(width 0.1524)
				(type default)
			)
			(layer "B.SilkS")
		)
		(fp_line
			(start -0.69215 -0.2921)
			(end -0.69215 0.2921)
			(stroke
				(width 0.1524)
				(type default)
			)
			(layer "B.SilkS")
		)
		(fp_line
			(start 0.51435 0.2794)
			(end 0.51435 -0.2794)
			(stroke
				(width 0.1)
				(type default)
			)
			(layer "B.Fab")
		)
		(fp_line
			(start 0.51435 -0.2794)
			(end -0.51435 -0.2794)
			(stroke
				(width 0.1)
				(type default)
			)
			(layer "B.Fab")
		)
		(fp_line
			(start -0.51435 0.2794)
			(end 0.51435 0.2794)
			(stroke
				(width 0.1)
				(type default)
			)
			(layer "B.Fab")
		)
		(fp_line
			(start -0.51435 -0.2794)
			(end -0.51435 0.2794)
			(stroke
				(width 0.1)
				(type default)
			)
			(layer "B.Fab")
		)
		(pad "1" smd circle
			(at 0.40005 0)
			(size 0 0)
			(layers "B.Cu" "B.Mask" "B.Paste")
			(net "VCCIO1")
		)
		(pad "2" smd circle
			(at -0.40005 0)
			(size 0 0)
			(layers "B.Cu" "B.Mask" "B.Paste")
			(net "GND")
		)
		(zone
			(layer "B.Cu")
			(hatch none 0.5)
			(connect_pads
				(clearance 0)
			)
			(min_thickness 0.25)
			(keepout
				(tracks not_allowed)
				(vias allowed)
				(pads allowed)
				(copperpour not_allowed)
				(footprints allowed)
			)
			(placement
				(enabled no)
				(sheetname "")
			)
			(fill
				(thermal_gap 0.5)
				(thermal_bridge_width 0.5)
				(island_removal_mode 0)
			)
			(polygon
				(pts
					(xy 18.068798 -94.874588) (xy 18.160238 -94.932754) (xy 18.359628 -94.932754) (xy 18.449798 -94.874588)
					(xy 18.449798 -94.699328) (xy 18.359628 -94.640908) (xy 18.160238 -94.640908) (xy 18.068798 -94.699074)
				)
			)
		)
	)
	(footprint ""
		(layer "B.Cu")
		(at 35.433 -36.195 -90)
		(property "Reference" "R159"
			(at 0 0 90)
			(layer "B.SilkS")
			(hide yes)
			(effects
				(font
					(size 1.27 1.27)
				)
				(justify mirror)
			)
		)
		(property "Value" ""
			(at 0 0 90)
			(layer "B.Fab")
			(effects
				(font
					(size 1.27 1.27)
				)
				(justify mirror)
			)
		)
		(duplicate_pad_numbers_are_jumpers no)
		(fp_line
			(start -0.7874 0.4064)
			(end 0.7874 0.4064)
			(stroke
				(width 0.1524)
				(type default)
			)
			(layer "B.SilkS")
		)
		(fp_line
			(start 0.7874 0.4064)
			(end 0.7874 -0.4064)
			(stroke
				(width 0.1524)
				(type default)
			)
			(layer "B.SilkS")
		)
		(fp_line
			(start -0.7874 -0.4064)
			(end -0.7874 0.4064)
			(stroke
				(width 0.1524)
				(type default)
			)
			(layer "B.SilkS")
		)
		(fp_line
			(start 0.7874 -0.4064)
			(end -0.7874 -0.4064)
			(stroke
				(width 0.1524)
				(type default)
			)
			(layer "B.SilkS")
		)
		(fp_line
			(start -0.67945 0.3048)
			(end -0.120396 0.3048)
			(stroke
				(width 0.1)
				(type default)
			)
			(layer "B.Fab")
		)
		(fp_line
			(start -0.120396 0.3048)
			(end -0.120396 0.2794)
			(stroke
				(width 0.1)
				(type default)
			)
			(layer "B.Fab")
		)
		(fp_line
			(start 0.12065 0.3048)
			(end 0.67945 0.3048)
			(stroke
				(width 0.1)
				(type default)
			)
			(layer "B.Fab")
		)
		(fp_line
			(start 0.67945 0.3048)
			(end 0.67945 -0.305054)
			(stroke
				(width 0.1)
				(type default)
			)
			(layer "B.Fab")
		)
		(fp_line
			(start -0.120396 0.2794)
			(end 0.12065 0.2794)
			(stroke
				(width 0.1)
				(type default)
			)
			(layer "B.Fab")
		)
		(fp_line
			(start 0.12065 0.2794)
			(end 0.12065 0.3048)
			(stroke
				(width 0.1)
				(type default)
			)
			(layer "B.Fab")
		)
		(fp_line
			(start -0.12065 -0.2794)
			(end -0.12065 -0.3048)
			(stroke
				(width 0.1)
				(type default)
			)
			(layer "B.Fab")
		)
		(fp_line
			(start 0.12065 -0.2794)
			(end -0.12065 -0.2794)
			(stroke
				(width 0.1)
				(type default)
			)
			(layer "B.Fab")
		)
		(fp_line
			(start -0.67945 -0.3048)
			(end -0.67945 0.3048)
			(stroke
				(width 0.1)
				(type default)
			)
			(layer "B.Fab")
		)
		(fp_line
			(start -0.12065 -0.3048)
			(end -0.67945 -0.3048)
			(stroke
				(width 0.1)
				(type default)
			)
			(layer "B.Fab")
		)
		(fp_line
			(start 0.12065 -0.305054)
			(end 0.12065 -0.2794)
			(stroke
				(width 0.1)
				(type default)
			)
			(layer "B.Fab")
		)
		(fp_line
			(start 0.67945 -0.305054)
			(end 0.12065 -0.305054)
			(stroke
				(width 0.1)
				(type default)
			)
			(layer "B.Fab")
		)
		(pad "1" smd circle
			(at 0.40005 0 90)
			(size 0 0)
			(layers "B.Cu" "B.Mask" "B.Paste")
			(net "FM_JTAG_TCK_MUX_BMC_SEL")
		)
		(pad "2" smd circle
			(at -0.40005 0 90)
			(size 0 0)
			(layers "B.Cu" "B.Mask" "B.Paste")
			(net "FM_JTAG_TCK_MUX_BMC_SEL_R1")
		)
	)
	(footprint ""
		(layer "B.Cu")
		(at 28.3464 -30.35935 -90)
		(property "Reference" "C206"
			(at 0 0 90)
			(layer "B.SilkS")
			(hide yes)
			(effects
				(font
					(size 1.27 1.27)
				)
				(justify mirror)
			)
		)
		(property "Value" ""
			(at 0 0 90)
			(layer "B.Fab")
			(effects
				(font
					(size 1.27 1.27)
				)
				(justify mirror)
			)
		)
		(duplicate_pad_numbers_are_jumpers no)
		(fp_line
			(start -0.7874 0.4064)
			(end 0.7874 0.4064)
			(stroke
				(width 0.1524)
				(type default)
			)
			(layer "B.SilkS")
		)
		(fp_line
			(start 0.7874 0.4064)
			(end 0.7874 -0.4064)
			(stroke
				(width 0.1524)
				(type default)
			)
			(layer "B.SilkS")
		)
		(fp_line
			(start -0.7874 -0.4064)
			(end -0.7874 0.4064)
			(stroke
				(width 0.1524)
				(type default)
			)
			(layer "B.SilkS")
		)
		(fp_line
			(start 0.7874 -0.4064)
			(end -0.7874 -0.4064)
			(stroke
				(width 0.1524)
				(type default)
			)
			(layer "B.SilkS")
		)
		(fp_line
			(start -0.67945 0.3048)
			(end -0.120396 0.3048)
			(stroke
				(width 0.1)
				(type default)
			)
			(layer "B.Fab")
		)
		(fp_line
			(start -0.120396 0.3048)
			(end -0.120396 0.2794)
			(stroke
				(width 0.1)
				(type default)
			)
			(layer "B.Fab")
		)
		(fp_line
			(start 0.12065 0.3048)
			(end 0.67945 0.3048)
			(stroke
				(width 0.1)
				(type default)
			)
			(layer "B.Fab")
		)
		(fp_line
			(start 0.67945 0.3048)
			(end 0.67945 -0.305054)
			(stroke
				(width 0.1)
				(type default)
			)
			(layer "B.Fab")
		)
		(fp_line
			(start -0.120396 0.2794)
			(end 0.12065 0.2794)
			(stroke
				(width 0.1)
				(type default)
			)
			(layer "B.Fab")
		)
		(fp_line
			(start 0.12065 0.2794)
			(end 0.12065 0.3048)
			(stroke
				(width 0.1)
				(type default)
			)
			(layer "B.Fab")
		)
		(fp_line
			(start -0.12065 -0.2794)
			(end -0.12065 -0.3048)
			(stroke
				(width 0.1)
				(type default)
			)
			(layer "B.Fab")
		)
		(fp_line
			(start 0.12065 -0.2794)
			(end -0.12065 -0.2794)
			(stroke
				(width 0.1)
				(type default)
			)
			(layer "B.Fab")
		)
		(fp_line
			(start -0.67945 -0.3048)
			(end -0.67945 0.3048)
			(stroke
				(width 0.1)
				(type default)
			)
			(layer "B.Fab")
		)
		(fp_line
			(start -0.12065 -0.3048)
			(end -0.67945 -0.3048)
			(stroke
				(width 0.1)
				(type default)
			)
			(layer "B.Fab")
		)
		(fp_line
			(start 0.12065 -0.305054)
			(end 0.12065 -0.2794)
			(stroke
				(width 0.1)
				(type default)
			)
			(layer "B.Fab")
		)
		(fp_line
			(start 0.67945 -0.305054)
			(end 0.12065 -0.305054)
			(stroke
				(width 0.1)
				(type default)
			)
			(layer "B.Fab")
		)
		(pad "1" smd circle
			(at 0.40005 0 90)
			(size 0 0)
			(layers "B.Cu" "B.Mask" "B.Paste")
			(net "V_DACG")
		)
		(pad "2" smd circle
			(at -0.40005 0 90)
			(size 0 0)
			(layers "B.Cu" "B.Mask" "B.Paste")
			(net "GND")
		)
	)
	(footprint ""
		(layer "B.Cu")
		(at 53.4924 -77.9018 -90)
		(property "Reference" "C255"
			(at 0 0 90)
			(layer "B.SilkS")
			(hide yes)
			(effects
				(font
					(size 1.27 1.27)
				)
				(justify mirror)
			)
		)
		(property "Value" ""
			(at 0 0 90)
			(layer "B.Fab")
			(effects
				(font
					(size 1.27 1.27)
				)
				(justify mirror)
			)
		)
		(duplicate_pad_numbers_are_jumpers no)
		(fp_line
			(start -0.7874 0.4064)
			(end 0.7874 0.4064)
			(stroke
				(width 0.1524)
				(type default)
			)
			(layer "B.SilkS")
		)
		(fp_line
			(start 0.7874 0.4064)
			(end 0.7874 -0.4064)
			(stroke
				(width 0.1524)
				(type default)
			)
			(layer "B.SilkS")
		)
		(fp_line
			(start -0.7874 -0.4064)
			(end -0.7874 0.4064)
			(stroke
				(width 0.1524)
				(type default)
			)
			(layer "B.SilkS")
		)
		(fp_line
			(start 0.7874 -0.4064)
			(end -0.7874 -0.4064)
			(stroke
				(width 0.1524)
				(type default)
			)
			(layer "B.SilkS")
		)
		(fp_line
			(start -0.67945 0.3048)
			(end -0.120396 0.3048)
			(stroke
				(width 0.1)
				(type default)
			)
			(layer "B.Fab")
		)
		(fp_line
			(start -0.120396 0.3048)
			(end -0.120396 0.2794)
			(stroke
				(width 0.1)
				(type default)
			)
			(layer "B.Fab")
		)
		(fp_line
			(start 0.12065 0.3048)
			(end 0.67945 0.3048)
			(stroke
				(width 0.1)
				(type default)
			)
			(layer "B.Fab")
		)
		(fp_line
			(start 0.67945 0.3048)
			(end 0.67945 -0.305054)
			(stroke
				(width 0.1)
				(type default)
			)
			(layer "B.Fab")
		)
		(fp_line
			(start -0.120396 0.2794)
			(end 0.12065 0.2794)
			(stroke
				(width 0.1)
				(type default)
			)
			(layer "B.Fab")
		)
		(fp_line
			(start 0.12065 0.2794)
			(end 0.12065 0.3048)
			(stroke
				(width 0.1)
				(type default)
			)
			(layer "B.Fab")
		)
		(fp_line
			(start -0.12065 -0.2794)
			(end -0.12065 -0.3048)
			(stroke
				(width 0.1)
				(type default)
			)
			(layer "B.Fab")
		)
		(fp_line
			(start 0.12065 -0.2794)
			(end -0.12065 -0.2794)
			(stroke
				(width 0.1)
				(type default)
			)
			(layer "B.Fab")
		)
		(fp_line
			(start -0.67945 -0.3048)
			(end -0.67945 0.3048)
			(stroke
				(width 0.1)
				(type default)
			)
			(layer "B.Fab")
		)
		(fp_line
			(start -0.12065 -0.3048)
			(end -0.67945 -0.3048)
			(stroke
				(width 0.1)
				(type default)
			)
			(layer "B.Fab")
		)
		(fp_line
			(start 0.12065 -0.305054)
			(end 0.12065 -0.2794)
			(stroke
				(width 0.1)
				(type default)
			)
			(layer "B.Fab")
		)
		(fp_line
			(start 0.67945 -0.305054)
			(end 0.12065 -0.305054)
			(stroke
				(width 0.1)
				(type default)
			)
			(layer "B.Fab")
		)
		(pad "1" smd circle
			(at 0.40005 0 90)
			(size 0 0)
			(layers "B.Cu" "B.Mask" "B.Paste")
			(net "P3V3_AUX")
		)
		(pad "2" smd circle
			(at -0.40005 0 90)
			(size 0 0)
			(layers "B.Cu" "B.Mask" "B.Paste")
			(net "GND")
		)
	)
)
